# T6G (Grand Teton) — schematic netlist excerpt (pin names and nets, part order shuffled) for the footprints in the layout excerpt that follows; sources: Cadence DE-HDL packaged netlist, KiCad conversion of 04192023_DAF0TMB3IC0_F0TG_MB_C_brd_V02_OCP.brd

J17  SCONN288_DDR506112002KQ  IO  pkg DDR288S_1-1VXC  page 88
  VIN_BULK0  = P12V_MEM_CPU0
  RFU0  = NC
  VIN_MGMT  = P3V3_AUX
  HSCL  = I3C_SPD_DDRC_CPU0_SCL
  HSDA  = I3C_SPD_DDRC_CPU0_SDA
  VSS0  = GND
  DQ0_A  = M_C_CPU0_SA_DQ<0>
  VSS1  = GND
  DQ1_A  = M_C_CPU0_SA_DQ<1>
  VSS2  = GND
  DQS0_A_T  = M_C_CPU0_SA_DQS_DP<0>
  DQS0_A_C  = M_C_CPU0_SA_DQS_DN<0>
  VSS3  = GND
  DQ4_A  = M_C_CPU0_SA_DQ<4>
  VSS4  = GND
  DQ5_A  = M_C_CPU0_SA_DQ<5>
  VSS5  = GND
  DQ8_A  = M_C_CPU0_SA_DQ<8>
  VSS6  = GND
  DQ9_A  = M_C_CPU0_SA_DQ<9>
  VSS7  = GND
  DQS1_A_T  = M_C_CPU0_SA_DQS_DP<1>
  DQS1_A_C  = M_C_CPU0_SA_DQS_DN<1>
  VSS8  = GND
  DQ12_A  = M_C_CPU0_SA_DQ<12>
  VSS9  = GND
  DQ13_A  = M_C_CPU0_SA_DQ<13>
  VSS10  = GND
  DQ16_A  = M_C_CPU0_SA_DQ<16>
  VSS11  = GND
  DQ17_A  = M_C_CPU0_SA_DQ<17>
  VSS12  = GND
  DQS2_A_T  = M_C_CPU0_SA_DQS_DP<2>
  DQS2_A_C  = M_C_CPU0_SA_DQS_DN<2>
  VSS13  = GND
  DQ20_A  = M_C_CPU0_SA_DQ<20>
  VSS14  = GND
  DQ21_A  = M_C_CPU0_SA_DQ<21>
  VSS15  = GND
  DQ24_A  = M_C_CPU0_SA_DQ<24>
  VSS16  = GND
  DQ25_A  = M_C_CPU0_SA_DQ<25>
  VSS17  = GND
  DQS3_A_T  = M_C_CPU0_SA_DQS_DP<3>
  DQS3_A_C  = M_C_CPU0_SA_DQS_DN<3>
  VSS18  = GND
  DQ28_A  = M_C_CPU0_SA_DQ<28>
  VSS19  = GND
  DQ29_A  = M_C_CPU0_SA_DQ<29>
  VSS20  = GND
  CB0_A  = M_C_CPU0_SA_CB<0>
  VSS21  = GND
  CB1_A  = M_C_CPU0_SA_CB<1>
  VSS22  = GND
  DQS4_A_T  = M_C_CPU0_SA_DQS_DP<4>
  DQS4_A_C  = M_C_CPU0_SA_DQS_DN<4>
  VSS23  = GND
  CB4_A  = M_C_CPU0_SA_CB<4>
  VSS24  = GND
  CB5_A  = M_C_CPU0_SA_CB<5>
  VSS25  = GND
  ALERT_N  = M_C_CPU0_ALERT_N
  VSS26  = GND
  CS0_A_N  = M_C_CPU0_SA_CS_N<0>
  VSS27  = GND
  CA0_A  = M_C_CPU0_SA_CA<0>
  VSS28  = GND
  CA2_A  = M_C_CPU0_SA_CA<2>
  VSS29  = GND
  CA4_A  = M_C_CPU0_SA_CA<4>
  VSS30  = GND
  CA6_A  = M_C_CPU0_SA_CA<6>
  VSS31  = GND
  PAR_A  = M_C_CPU0_SA_PAR
  VSS32  = GND
  CA0_B  = M_C_CPU0_SB_CA<0>
  VSS33  = GND
  CA2_B  = M_C_CPU0_SB_CA<2>
  VSS34  = GND
  CA4_B  = M_C_CPU0_SB_CA<4>
  VSS35  = GND
  CA6_B  = M_C_CPU0_SB_CA<6>
  VSS36  = GND
  CS0_B_N  = M_C_CPU0_SB_CS_N<0>
  VSS37  = GND
  \lbd||rsp_a_n\  = M_C_CPU0_SA_RSP<0>
  \lbs||rsp_b_n\  = M_C_CPU0_SB_RSP<0>
  VSS38  = GND
  CB4_B  = M_C_CPU0_SB_CB<4>
  VSS39  = GND
  CB5_B  = M_C_CPU0_SB_CB<5>
  VSS40  = GND
  \dqs9_b_t||tdqs9_b_t||dbi4_b_n\  = M_C_CPU0_SB_DQS_DP<9>
  \dqs9_b_c||tdqs9_b_c\  = M_C_CPU0_SB_DQS_DN<9>
  VSS41  = GND
  CB0_B  = M_C_CPU0_SB_CB<0>
  VSS42  = GND
  CB1_B  = M_C_CPU0_SB_CB<1>
  VSS43  = GND
  DQ0_B  = M_C_CPU0_SB_DQ<0>
  VSS44  = GND
  DQ1_B  = M_C_CPU0_SB_DQ<1>
  VSS45  = GND
  DQS0_B_T  = M_C_CPU0_SB_DQS_DP<0>
  DQS0_B_C  = M_C_CPU0_SB_DQS_DN<0>
  VSS46  = GND
  DQ4_B  = M_C_CPU0_SB_DQ<4>
  VSS47  = GND
  DQ5_B  = M_C_CPU0_SB_DQ<5>
  VSS48  = GND
  DQ8_B  = M_C_CPU0_SB_DQ<8>
  VSS49  = GND
  DQ9_B  = M_C_CPU0_SB_DQ<9>
  VSS50  = GND
  DQS1_B_T  = M_C_CPU0_SB_DQS_DP<1>
  DQS1_B_C  = M_C_CPU0_SB_DQS_DN<1>
  VSS51  = GND
  DQ12_B  = M_C_CPU0_SB_DQ<12>
  VSS52  = GND
  DQ13_B  = M_C_CPU0_SB_DQ<13>
  VSS53  = GND
  DQ16_B  = M_C_CPU0_SB_DQ<16>
  VSS54  = GND
  DQ17_B  = M_C_CPU0_SB_DQ<17>
  VSS55  = GND
  DQS2_B_T  = M_C_CPU0_SB_DQS_DP<2>
  DQS2_B_C  = M_C_CPU0_SB_DQS_DN<2>
  VSS56  = GND
  DQ20_B  = M_C_CPU0_SB_DQ<20>
  VSS57  = GND
  DQ21_B  = M_C_CPU0_SB_DQ<21>
  VSS58  = GND
  DQ24_B  = M_C_CPU0_SB_DQ<24>
  VSS59  = GND
  DQ25_B  = M_C_CPU0_SB_DQ<25>
  VSS60  = GND
  DQS3_B_T  = M_C_CPU0_SB_DQS_DP<3>
  DQS3_B_C  = M_C_CPU0_SB_DQS_DN<3>
  VSS61  = GND
  DQ28_B  = M_C_CPU0_SB_DQ<28>
  VSS62  = GND
  DQ29_B  = M_C_CPU0_SB_DQ<29>
  VSS63  = GND
  RFU1  = NC
  VIN_BULK1  = P12V_MEM_CPU0
  VIN_BULK2  = P12V_MEM_CPU0
  \pwr_good||fail_n\  = PWRGD_CHC_CPU0_DIMM
  HAS  = PD_CHC_CPU0_DIMM_SAA
  RFU2  = NC
  RFU3  = NC
  VSS64  = GND
  DQ2_A  = M_C_CPU0_SA_DQ<2>
  VSS65  = GND
  DQ3_A  = M_C_CPU0_SA_DQ<3>
  VSS66  = GND
  \dqs5_a_c||tdqs5_a_c||dqs5_a_t||tdqs5_a_t\  = M_C_CPU0_SA_DQS_DN<5>
  \dqs5_a_t||tdqs5_a_t\  = M_C_CPU0_SA_DQS_DP<5>
  VSS67  = GND
  DQ6_A  = M_C_CPU0_SA_DQ<6>
  VSS68  = GND
  DQ7_A  = M_C_CPU0_SA_DQ<7>
  VSS69  = GND
  DQ10_A  = M_C_CPU0_SA_DQ<10>
  VSS70  = GND
  DQ11_A  = M_C_CPU0_SA_DQ<11>
  VSS71  = GND
  \dqs6_a_c||tdqs6_a_c||dqs6_a_t||tdqs6_a_t\  = M_C_CPU0_SA_DQS_DN<6>
  \dqs6_a_t||tdqs6_a_t\  = M_C_CPU0_SA_DQS_DP<6>
  VSS72  = GND
  DQ14_A  = M_C_CPU0_SA_DQ<14>
  VSS73  = GND
  DQ15_A  = M_C_CPU0_SA_DQ<15>
  VSS74  = GND
  DQ18_A  = M_C_CPU0_SA_DQ<18>
  VSS75  = GND
  DQ19_A  = M_C_CPU0_SA_DQ<19>
  VSS76  = GND
  \dqs7_a_c||tdqs7_a_c\  = M_C_CPU0_SA_DQS_DN<7>
  \dqs7_a_t||tdqs7_a_t\  = M_C_CPU0_SA_DQS_DP<7>
  VSS77  = GND
  DQ22_A  = M_C_CPU0_SA_DQ<22>
  VSS78  = GND
  DQ23_A  = M_C_CPU0_SA_DQ<23>
  VSS79  = GND
  DQ26_A  = M_C_CPU0_SA_DQ<26>
  VSS80  = GND
  DQ27_A  = M_C_CPU0_SA_DQ<27>
  VSS81  = GND
  \dqs8_a_c||tdqs8_a_c\  = M_C_CPU0_SA_DQS_DN<8>
  \dqs8_a_t||tdqs8_a_t\  = M_C_CPU0_SA_DQS_DP<8>
  VSS82  = GND
  DQ30_A  = M_C_CPU0_SA_DQ<30>
  VSS83  = GND
  DQ31_A  = M_C_CPU0_SA_DQ<31>
  VSS84  = GND
  CB2_A  = M_C_CPU0_SA_CB<2>
  VSS85  = GND
  CB3_A  = M_C_CPU0_SA_CB<3>
  VSS86  = GND
  \dqs9_a_c||tdqs9_a_c\  = M_C_CPU0_SA_DQS_DN<9>
  \dqs9_a_t||tdqs9_a_t\  = M_C_CPU0_SA_DQS_DP<9>
  VSS87  = GND
  CB6_A  = M_C_CPU0_SA_CB<6>
  VSS88  = GND
  CB7_A  = M_C_CPU0_SA_CB<7>
  VSS89  = GND
  RESET_N  = M_C_CPU0_RESET_N
  VSS90  = GND
  CS1_A_N  = M_C_CPU0_SA_CS_N<1>
  VSS91  = GND
  CA1_A  = M_C_CPU0_SA_CA<1>
  VSS92  = GND
  CA3_A  = M_C_CPU0_SA_CA<3>
  VSS93  = GND
  CA5_A  = M_C_CPU0_SA_CA<5>
  VSS94  = GND
  CK_T  = M_C_CPU0_CLK_DP<0>
  CK_C  = M_C_CPU0_CLK_DN<0>
  VSS95  = GND
  RFU4  = NC
  CA1_B  = M_C_CPU0_SB_CA<1>
  VSS96  = GND
  CA3_B  = M_C_CPU0_SB_CA<3>
  VSS97  = GND
  CA5_B  = M_C_CPU0_SB_CA<5>
  VSS98  = GND
  PAR_B  = M_C_CPU0_SB_PAR
  VSS99  = GND
  CS1_B_N  = M_C_CPU0_SB_CS_N<1>
  VSS100  = GND
  RFU5  = NC
  RFU6  = NC
  VSS101  = GND
  CB6_B  = M_C_CPU0_SB_CB<6>
  VSS102  = GND
  CB7_B  = M_C_CPU0_SB_CB<7>
  VSS103  = GND
  DQS4_B_C  = M_C_CPU0_SB_DQS_DN<4>
  DQS4_B_T  = M_C_CPU0_SB_DQS_DP<4>
  VSS104  = GND
  CB2_B  = M_C_CPU0_SB_CB<2>
  VSS105  = GND
  CB3_B  = M_C_CPU0_SB_CB<3>
  VSS106  = GND
  DQ2_B  = M_C_CPU0_SB_DQ<2>
  VSS107  = GND
  DQ3_B  = M_C_CPU0_SB_DQ<3>
  VSS108  = GND
  \dqs5_b_c||tdqs5_b_c\  = M_C_CPU0_SB_DQS_DN<5>
  \dqs5_b_t||tdqs5_b_t\  = M_C_CPU0_SB_DQS_DP<5>
  VSS109  = GND
  DQ6_B  = M_C_CPU0_SB_DQ<6>
  VSS110  = GND
  DQ7_B  = M_C_CPU0_SB_DQ<7>
  VSS111  = GND
  DQ10_B  = M_C_CPU0_SB_DQ<10>
  VSS112  = GND
  DQ11_B  = M_C_CPU0_SB_DQ<11>
  VSS113  = GND
  \dqs6_b_c||tdqs6_b_c\  = M_C_CPU0_SB_DQS_DN<6>
  \dqs6_b_t||tdqs6_b_t\  = M_C_CPU0_SB_DQS_DP<6>
  VSS114  = GND
  DQ14_B  = M_C_CPU0_SB_DQ<14>
  VSS115  = GND
  DQ15_B  = M_C_CPU0_SB_DQ<15>
  VSS116  = GND
  DQ18_B  = M_C_CPU0_SB_DQ<18>
  VSS117  = GND
  DQ19_B  = M_C_CPU0_SB_DQ<19>
  VSS118  = GND
  \dqs7_b_c||tdqs7_b_c\  = M_C_CPU0_SB_DQS_DN<7>
  \dqs7_b_t||tdqs7_b_t\  = M_C_CPU0_SB_DQS_DP<7>
  VSS119  = GND
  DQ22_B  = M_C_CPU0_SB_DQ<22>
  VSS120  = GND
  DQ23_B  = M_C_CPU0_SB_DQ<23>
  VSS121  = GND
  DQ26_B  = M_C_CPU0_SB_DQ<26>
  VSS122  = GND
  DQ27_B  = M_C_CPU0_SB_DQ<27>
  VSS123  = GND
  \dqs8_b_c||tdqs8_b_c\  = M_C_CPU0_SB_DQS_DN<8>
  \dqs8_b_t||tdqs8_b_t\  = M_C_CPU0_SB_DQS_DP<8>
  VSS124  = GND
  DQ30_B  = M_C_CPU0_SB_DQ<30>
  VSS125  = GND
  DQ31_B  = M_C_CPU0_SB_DQ<31>
  VSS126  = GND
  G1  = GND
  G2  = GND
  G3  = GND

(kicad_pcb
	(version 20260206)
	(generator "pcbnew")
	(generator_version "10.0")
	(general
		(thickness 1.6)
		(legacy_teardrops no)
	)
	(paper "A4")
	(title_block
		(title "04192023_DAF0TMB3IC0_F0TG_MB_C_brd_V02_OCP.brd")
		(comment 1 "Grand Teton / footprint 4167 of 8354 (J17), pads 93-138 of 291")
	)
	(layers
		(0 "F.Cu" signal "TOP")
		(4 "In1.Cu" signal "GND")
		(6 "In2.Cu" signal "IN1")
		(8 "In3.Cu" signal "GND1")
		(10 "In4.Cu" signal "IN2")
		(12 "In5.Cu" signal "GND2")
		(14 "In6.Cu" signal "IN3")
		(16 "In7.Cu" signal "GND3")
		(18 "In8.Cu" signal "VCC")
		(20 "In9.Cu" signal "VCC1")
		(22 "In10.Cu" signal "GND4")
		(24 "In11.Cu" signal "IN4")
		(26 "In12.Cu" signal "GND5")
		(28 "In13.Cu" signal "IN5")
		(30 "In14.Cu" signal "GND6")
		(32 "In15.Cu" signal "IN6")
		(34 "In16.Cu" signal "GND7")
		(2 "B.Cu" signal "BOTTOM")
		(9 "F.Adhes" user "F.Adhesive")
		(11 "B.Adhes" user "B.Adhesive")
		(13 "F.Paste" user "Package Geometry/Pastemask Top")
		(15 "B.Paste" user "Package Geometry/Pastemask Bottom")
		(5 "F.SilkS" user "Ref Des/Silkscreen Top")
		(7 "B.SilkS" user "Ref Des/Silkscreen Bottom")
		(1 "F.Mask" user "Board Geometry/Soldermask Top")
		(3 "B.Mask" user "Board Geometry/Soldermask Bottom")
		(17 "Dwgs.User" user "User.Drawings")
		(19 "Cmts.User" user "User.Comments")
		(21 "Eco1.User" user "User.Eco1")
		(23 "Eco2.User" user "User.Eco2")
		(25 "Edge.Cuts" user "Board Geometry/Outline")
		(27 "Margin" user)
		(31 "F.CrtYd" user "Package Geometry/Place Bound Top")
		(29 "B.CrtYd" user "Package Geometry/Place Bound Bottom")
		(35 "F.Fab" user "Ref Des/Assembly Top")
		(33 "B.Fab" user "Ref Des/Assembly Bottom")
	)
	(footprint ""
		(layer "F.Cu")
		(at 290.230052 -255.560068 180)
		(property "Reference" "J17"
			(at -2.2098 -81.984088 0)
			(unlocked yes)
			(layer "F.SilkS")
			(effects
				(font
					(size 0.7874 0.5842)
					(thickness 0.1524)
				)
			)
		)
		(property "Value" ""
			(at 0 0 180)
			(layer "F.Fab")
			(effects
				(font
					(size 1.27 1.27)
				)
			)
		)
		(duplicate_pad_numbers_are_jumpers no)
		(pad "93" smd rect
			(at -2.050034 19.975068 90)
			(size 0.519938 1.4986)
			(layers "F.Cu" "F.Mask" "F.Paste")
			(net "M_C_CPU0_SB_DQS_DP<9>")
		)
		(pad "94" smd rect
			(at -2.050034 20.824952 90)
			(size 0.519938 1.4986)
			(layers "F.Cu" "F.Mask" "F.Paste")
			(net "M_C_CPU0_SB_DQS_DN<9>")
		)
		(pad "95" smd rect
			(at -2.050034 21.67509 90)
			(size 0.519938 1.4986)
			(layers "F.Cu" "F.Mask" "F.Paste")
			(net "GND")
		)
		(pad "96" smd rect
			(at -2.050034 22.524974 90)
			(size 0.519938 1.4986)
			(layers "F.Cu" "F.Mask" "F.Paste")
			(net "M_C_CPU0_SB_CB<0>")
		)
		(pad "97" smd rect
			(at -2.050034 23.375112 90)
			(size 0.519938 1.4986)
			(layers "F.Cu" "F.Mask" "F.Paste")
			(net "GND")
		)
		(pad "98" smd rect
			(at -2.050034 24.224996 90)
			(size 0.519938 1.4986)
			(layers "F.Cu" "F.Mask" "F.Paste")
			(net "M_C_CPU0_SB_CB<1>")
		)
		(pad "99" smd rect
			(at -2.050034 25.07488 90)
			(size 0.519938 1.4986)
			(layers "F.Cu" "F.Mask" "F.Paste")
			(net "GND")
		)
		(pad "100" smd rect
			(at -2.050034 25.925018 90)
			(size 0.519938 1.4986)
			(layers "F.Cu" "F.Mask" "F.Paste")
			(net "M_C_CPU0_SB_DQ<0>")
		)
		(pad "101" smd rect
			(at -2.050034 26.774902 90)
			(size 0.519938 1.4986)
			(layers "F.Cu" "F.Mask" "F.Paste")
			(net "GND")
		)
		(pad "102" smd rect
			(at -2.050034 27.62504 90)
			(size 0.519938 1.4986)
			(layers "F.Cu" "F.Mask" "F.Paste")
			(net "M_C_CPU0_SB_DQ<1>")
		)
		(pad "103" smd rect
			(at -2.050034 28.474924 90)
			(size 0.519938 1.4986)
			(layers "F.Cu" "F.Mask" "F.Paste")
			(net "GND")
		)
		(pad "104" smd rect
			(at -2.050034 29.325062 90)
			(size 0.519938 1.4986)
			(layers "F.Cu" "F.Mask" "F.Paste")
			(net "M_C_CPU0_SB_DQS_DP<0>")
		)
		(pad "105" smd rect
			(at -2.050034 30.174946 90)
			(size 0.519938 1.4986)
			(layers "F.Cu" "F.Mask" "F.Paste")
			(net "M_C_CPU0_SB_DQS_DN<0>")
		)
		(pad "106" smd rect
			(at -2.050034 31.025084 90)
			(size 0.519938 1.4986)
			(layers "F.Cu" "F.Mask" "F.Paste")
			(net "GND")
		)
		(pad "107" smd rect
			(at -2.050034 31.874968 90)
			(size 0.519938 1.4986)
			(layers "F.Cu" "F.Mask" "F.Paste")
			(net "M_C_CPU0_SB_DQ<4>")
		)
		(pad "108" smd rect
			(at -2.050034 32.725106 90)
			(size 0.519938 1.4986)
			(layers "F.Cu" "F.Mask" "F.Paste")
			(net "GND")
		)
		(pad "109" smd rect
			(at -2.050034 33.57499 90)
			(size 0.519938 1.4986)
			(layers "F.Cu" "F.Mask" "F.Paste")
			(net "M_C_CPU0_SB_DQ<5>")
		)
		(pad "110" smd rect
			(at -2.050034 34.425128 90)
			(size 0.519938 1.4986)
			(layers "F.Cu" "F.Mask" "F.Paste")
			(net "GND")
		)
		(pad "111" smd rect
			(at -2.050034 35.275012 90)
			(size 0.519938 1.4986)
			(layers "F.Cu" "F.Mask" "F.Paste")
			(net "M_C_CPU0_SB_DQ<8>")
		)
		(pad "112" smd rect
			(at -2.050034 36.124896 90)
			(size 0.519938 1.4986)
			(layers "F.Cu" "F.Mask" "F.Paste")
			(net "GND")
		)
		(pad "113" smd rect
			(at -2.050034 36.975034 90)
			(size 0.519938 1.4986)
			(layers "F.Cu" "F.Mask" "F.Paste")
			(net "M_C_CPU0_SB_DQ<9>")
		)
		(pad "114" smd rect
			(at -2.050034 37.824918 90)
			(size 0.519938 1.4986)
			(layers "F.Cu" "F.Mask" "F.Paste")
			(net "GND")
		)
		(pad "115" smd rect
			(at -2.050034 38.675056 90)
			(size 0.519938 1.4986)
			(layers "F.Cu" "F.Mask" "F.Paste")
			(net "M_C_CPU0_SB_DQS_DP<1>")
		)
		(pad "116" smd rect
			(at -2.050034 39.52494 90)
			(size 0.519938 1.4986)
			(layers "F.Cu" "F.Mask" "F.Paste")
			(net "M_C_CPU0_SB_DQS_DN<1>")
		)
		(pad "117" smd rect
			(at -2.050034 40.375078 90)
			(size 0.519938 1.4986)
			(layers "F.Cu" "F.Mask" "F.Paste")
			(net "GND")
		)
		(pad "118" smd rect
			(at -2.050034 41.224962 90)
			(size 0.519938 1.4986)
			(layers "F.Cu" "F.Mask" "F.Paste")
			(net "M_C_CPU0_SB_DQ<12>")
		)
		(pad "119" smd rect
			(at -2.050034 42.0751 90)
			(size 0.519938 1.4986)
			(layers "F.Cu" "F.Mask" "F.Paste")
			(net "GND")
		)
		(pad "120" smd rect
			(at -2.050034 42.924984 90)
			(size 0.519938 1.4986)
			(layers "F.Cu" "F.Mask" "F.Paste")
			(net "M_C_CPU0_SB_DQ<13>")
		)
		(pad "121" smd rect
			(at -2.050034 43.775122 90)
			(size 0.519938 1.4986)
			(layers "F.Cu" "F.Mask" "F.Paste")
			(net "GND")
		)
		(pad "122" smd rect
			(at -2.050034 44.625006 90)
			(size 0.519938 1.4986)
			(layers "F.Cu" "F.Mask" "F.Paste")
			(net "M_C_CPU0_SB_DQ<16>")
		)
		(pad "123" smd rect
			(at -2.050034 45.47489 90)
			(size 0.519938 1.4986)
			(layers "F.Cu" "F.Mask" "F.Paste")
			(net "GND")
		)
		(pad "124" smd rect
			(at -2.050034 46.325028 90)
			(size 0.519938 1.4986)
			(layers "F.Cu" "F.Mask" "F.Paste")
			(net "M_C_CPU0_SB_DQ<17>")
		)
		(pad "125" smd rect
			(at -2.050034 47.174912 90)
			(size 0.519938 1.4986)
			(layers "F.Cu" "F.Mask" "F.Paste")
			(net "GND")
		)
		(pad "126" smd rect
			(at -2.050034 48.02505 90)
			(size 0.519938 1.4986)
			(layers "F.Cu" "F.Mask" "F.Paste")
			(net "M_C_CPU0_SB_DQS_DP<2>")
		)
		(pad "127" smd rect
			(at -2.050034 48.874934 90)
			(size 0.519938 1.4986)
			(layers "F.Cu" "F.Mask" "F.Paste")
			(net "M_C_CPU0_SB_DQS_DN<2>")
		)
		(pad "128" smd rect
			(at -2.050034 49.725072 90)
			(size 0.519938 1.4986)
			(layers "F.Cu" "F.Mask" "F.Paste")
			(net "GND")
		)
		(pad "129" smd rect
			(at -2.050034 50.574956 90)
			(size 0.519938 1.4986)
			(layers "F.Cu" "F.Mask" "F.Paste")
			(net "M_C_CPU0_SB_DQ<20>")
		)
		(pad "130" smd rect
			(at -2.050034 51.425094 90)
			(size 0.519938 1.4986)
			(layers "F.Cu" "F.Mask" "F.Paste")
			(net "GND")
		)
		(pad "131" smd rect
			(at -2.050034 52.274978 90)
			(size 0.519938 1.4986)
			(layers "F.Cu" "F.Mask" "F.Paste")
			(net "M_C_CPU0_SB_DQ<21>")
		)
		(pad "132" smd rect
			(at -2.050034 53.125116 90)
			(size 0.519938 1.4986)
			(layers "F.Cu" "F.Mask" "F.Paste")
			(net "GND")
		)
		(pad "133" smd rect
			(at -2.050034 53.975 90)
			(size 0.519938 1.4986)
			(layers "F.Cu" "F.Mask" "F.Paste")
			(net "M_C_CPU0_SB_DQ<24>")
		)
		(pad "134" smd rect
			(at -2.050034 54.824884 90)
			(size 0.519938 1.4986)
			(layers "F.Cu" "F.Mask" "F.Paste")
			(net "GND")
		)
		(pad "135" smd rect
			(at -2.050034 55.675022 90)
			(size 0.519938 1.4986)
			(layers "F.Cu" "F.Mask" "F.Paste")
			(net "M_C_CPU0_SB_DQ<25>")
		)
		(pad "136" smd rect
			(at -2.050034 56.524906 90)
			(size 0.519938 1.4986)
			(layers "F.Cu" "F.Mask" "F.Paste")
			(net "GND")
		)
		(pad "137" smd rect
			(at -2.050034 57.375044 90)
			(size 0.519938 1.4986)
			(layers "F.Cu" "F.Mask" "F.Paste")
			(net "M_C_CPU0_SB_DQS_DP<3>")
		)
		(pad "138" smd rect
			(at -2.050034 58.224928 90)
			(size 0.519938 1.4986)
			(layers "F.Cu" "F.Mask" "F.Paste")
			(net "M_C_CPU0_SB_DQS_DN<3>")
		)
	)
)
